(kicad_pcb
	(version 20260206)
	(generator "pcbnew")
	(generator_version "10.0")
	(general
		(thickness 1.6)
		(legacy_teardrops no)
	)
	(paper "A4")
	(title_block
		(title "baseboard — 13948-1b.1110WZS1818.brd")
		(comment 1 "Honey Badger (Wiwynn) / footprints 2263-2269 of 2523")
	)
	(layers
		(0 "F.Cu" signal "TOP")
		(4 "In1.Cu" signal "L2GND")
		(6 "In2.Cu" signal "L3")
		(8 "In3.Cu" signal "L4VCC")
		(10 "In4.Cu" signal "L5VCC")
		(12 "In5.Cu" signal "L6")
		(14 "In6.Cu" signal "L7GND")
		(2 "B.Cu" signal "BOTTOM")
		(9 "F.Adhes" user "F.Adhesive")
		(11 "B.Adhes" user "B.Adhesive")
		(13 "F.Paste" user "Package Geometry/Pastemask Top")
		(15 "B.Paste" user "Package Geometry/Pastemask Bottom")
		(5 "F.SilkS" user "Ref Des/Silkscreen Top")
		(7 "B.SilkS" user "Ref Des/Silkscreen Bottom")
		(1 "F.Mask" user "Board Geometry/Soldermask Top")
		(3 "B.Mask" user "Board Geometry/Soldermask Bottom")
		(17 "Dwgs.User" user "User.Drawings")
		(19 "Cmts.User" user "User.Comments")
		(21 "Eco1.User" user "User.Eco1")
		(23 "Eco2.User" user "User.Eco2")
		(25 "Edge.Cuts" user "Board Geometry/Outline")
		(27 "Margin" user)
		(31 "F.CrtYd" user "Package Geometry/Place Bound Top")
		(29 "B.CrtYd" user "Package Geometry/Place Bound Bottom")
		(35 "F.Fab" user "Ref Des/Assembly Top")
		(33 "B.Fab" user "Ref Des/Assembly Bottom")
	)
	(footprint ""
		(layer "B.Cu")
		(at 124.441966 -37.973 -90)
		(property "Reference" "SQ1"
			(at 0 0 90)
			(layer "B.SilkS")
			(hide yes)
			(effects
				(font
					(size 1.27 1.27)
				)
				(justify mirror)
			)
		)
		(property "Value" "AO3400A-GP"
			(at -0.0254 -12.3444 270)
			(unlocked yes)
			(layer "B.Fab")
			(hide yes)
			(effects
				(font
					(size 1.016 1.016)
					(thickness 0.1524)
				)
				(justify mirror)
			)
		)
		(property "Device Type" "SOT23DGS2D8H50"
			(at -0.0254 -14.2494 270)
			(unlocked yes)
			(layer "B.Fab")
			(hide yes)
			(effects
				(font
					(size 1.016 1.016)
					(thickness 0.1524)
				)
				(justify mirror)
			)
		)
		(duplicate_pad_numbers_are_jumpers no)
		(fp_line
			(start -1.7018 0.254)
			(end 1.7018 0.254)
			(stroke
				(width 0.1524)
				(type default)
			)
			(layer "B.SilkS")
		)
		(fp_line
			(start 1.7018 0.254)
			(end 1.7018 -0.254)
			(stroke
				(width 0.1524)
				(type default)
			)
			(layer "B.SilkS")
		)
		(fp_line
			(start -1.7018 -0.254)
			(end -1.7018 0.254)
			(stroke
				(width 0.1524)
				(type default)
			)
			(layer "B.SilkS")
		)
		(fp_line
			(start 1.7018 -0.254)
			(end -1.7018 -0.254)
			(stroke
				(width 0.1524)
				(type default)
			)
			(layer "B.SilkS")
		)
		(fp_rect
			(start 1.778 1.9812)
			(end -1.778 -1.9812)
			(stroke
				(width 0)
				(type default)
			)
			(fill no)
			(layer "B.CrtYd")
		)
		(fp_poly
			(pts
				(xy 1.778 -1.9812) (xy -1.778 -1.9812) (xy -1.778 1.9812) (xy 1.778 1.9812)
			)
			(stroke
				(width 0)
				(type default)
			)
			(fill no)
			(layer "B.Fab")
		)
		(pad "D" smd custom
			(at 0 -1.1176 90)
			(size 0.254 0.254)
			(layers "B.Cu" "B.Mask" "B.Paste")
			(net "SYS_HB_LED_D")
			(options
				(clearance outline)
				(anchor circle)
			)
			(primitives
				(gr_poly
					(pts
						(arc
							(start -0.508 0.4064)
							(mid -0.448484 0.550084)
							(end -0.3048 0.6096)
						)
						(arc
							(start 0.3048 0.6096)
							(mid 0.448484 0.550084)
							(end 0.508 0.4064)
						)
						(arc
							(start 0.508 -0.4064)
							(mid 0.448484 -0.550084)
							(end 0.3048 -0.6096)
						)
						(arc
							(start -0.3048 -0.6096)
							(mid -0.448484 -0.550084)
							(end -0.508 -0.4064)
						)
					)
					(width 0)
					(fill yes)
				)
			)
		)
		(pad "G" smd custom
			(at 1.016 1.1176 90)
			(size 0.254 0.254)
			(layers "B.Cu" "B.Mask" "B.Paste")
			(net "SYS_HB_LED")
			(options
				(clearance outline)
				(anchor circle)
			)
			(primitives
				(gr_poly
					(pts
						(arc
							(start -0.508 0.4064)
							(mid -0.448484 0.550084)
							(end -0.3048 0.6096)
						)
						(arc
							(start 0.3048 0.6096)
							(mid 0.448484 0.550084)
							(end 0.508 0.4064)
						)
						(arc
							(start 0.508 -0.4064)
							(mid 0.448484 -0.550084)
							(end 0.3048 -0.6096)
						)
						(arc
							(start -0.3048 -0.6096)
							(mid -0.448484 -0.550084)
							(end -0.508 -0.4064)
						)
					)
					(width 0)
					(fill yes)
				)
			)
		)
		(pad "S" smd custom
			(at -1.016 1.1176 90)
			(size 0.254 0.254)
			(layers "B.Cu" "B.Mask" "B.Paste")
			(net "GND")
			(options
				(clearance outline)
				(anchor circle)
			)
			(primitives
				(gr_poly
					(pts
						(arc
							(start -0.508 0.4064)
							(mid -0.448484 0.550084)
							(end -0.3048 0.6096)
						)
						(arc
							(start 0.3048 0.6096)
							(mid 0.448484 0.550084)
							(end 0.508 0.4064)
						)
						(arc
							(start 0.508 -0.4064)
							(mid 0.448484 -0.550084)
							(end 0.3048 -0.6096)
						)
						(arc
							(start -0.3048 -0.6096)
							(mid -0.448484 -0.550084)
							(end -0.508 -0.4064)
						)
					)
					(width 0)
					(fill yes)
				)
			)
		)
	)
	(footprint ""
		(layer "B.Cu")
		(at 340.110318 -135.385048 90)
		(property "Reference" "R559"
			(at 0 0 90)
			(layer "B.SilkS")
			(hide yes)
			(effects
				(font
					(size 1.27 1.27)
				)
				(justify mirror)
			)
		)
		(property "Value" "0R3J-0-U-GP"
			(at 0.0254 -2.5146 90)
			(unlocked yes)
			(layer "B.Fab")
			(hide yes)
			(effects
				(font
					(size 1.016 1.016)
					(thickness 0.1524)
				)
				(justify mirror)
			)
		)
		(property "Device Type" "R603H22"
			(at 0.0254 -4.0386 90)
			(unlocked yes)
			(layer "B.Fab")
			(hide yes)
			(effects
				(font
					(size 1.016 1.016)
					(thickness 0.1524)
				)
				(justify mirror)
			)
		)
		(duplicate_pad_numbers_are_jumpers no)
		(fp_line
			(start 0.4826 0)
			(end 0.2032 0)
			(stroke
				(width 0.2032)
				(type default)
			)
			(layer "B.SilkS")
		)
		(fp_line
			(start -0.2032 0)
			(end -0.4826 0)
			(stroke
				(width 0.2032)
				(type default)
			)
			(layer "B.SilkS")
		)
		(fp_rect
			(start 0.5842 1.3335)
			(end -0.5842 -1.3335)
			(stroke
				(width 0)
				(type default)
			)
			(fill no)
			(layer "B.CrtYd")
		)
		(fp_rect
			(start 0.5842 1.3335)
			(end -0.5842 -1.3335)
			(stroke
				(width 0)
				(type default)
			)
			(fill no)
			(layer "B.Fab")
		)
		(pad "1" smd custom
			(at 0 -0.762 270)
			(size 0.2159 0.2159)
			(layers "B.Cu" "B.Mask" "B.Paste")
			(net "USB_P0_DN")
			(options
				(clearance outline)
				(anchor circle)
			)
			(primitives
				(gr_poly
					(pts
						(arc
							(start -0.3302 0.4318)
							(mid -0.402042 0.402042)
							(end -0.4318 0.3302)
						)
						(arc
							(start -0.4318 -0.3302)
							(mid -0.402042 -0.402042)
							(end -0.3302 -0.4318)
						)
						(arc
							(start 0.3302 -0.4318)
							(mid 0.402042 -0.402042)
							(end 0.4318 -0.3302)
						)
						(arc
							(start 0.4318 0.3302)
							(mid 0.402042 0.402042)
							(end 0.3302 0.4318)
						)
					)
					(width 0)
					(fill yes)
				)
			)
		)
		(pad "2" smd custom
			(at 0 0.762 270)
			(size 0.2159 0.2159)
			(layers "B.Cu" "B.Mask" "B.Paste")
			(net "USB_DN_R")
			(options
				(clearance outline)
				(anchor circle)
			)
			(primitives
				(gr_poly
					(pts
						(arc
							(start -0.3302 0.4318)
							(mid -0.402042 0.402042)
							(end -0.4318 0.3302)
						)
						(arc
							(start -0.4318 -0.3302)
							(mid -0.402042 -0.402042)
							(end -0.3302 -0.4318)
						)
						(arc
							(start 0.3302 -0.4318)
							(mid 0.402042 -0.402042)
							(end 0.4318 -0.3302)
						)
						(arc
							(start 0.4318 0.3302)
							(mid 0.402042 0.402042)
							(end 0.3302 0.4318)
						)
					)
					(width 0)
					(fill yes)
				)
			)
		)
	)
	(footprint ""
		(layer "B.Cu")
		(at 121.925842 -107.894882 180)
		(property "Reference" "SC1177"
			(at 0 0 0)
			(layer "B.SilkS")
			(hide yes)
			(effects
				(font
					(size 1.27 1.27)
				)
				(justify mirror)
			)
		)
		(property "Value" "SC22U6D3V5MX-2GP"
			(at 0.0762 -6.1214 180)
			(unlocked yes)
			(layer "B.Fab")
			(hide yes)
			(effects
				(font
					(size 1.016 1.016)
					(thickness 0.1524)
				)
				(justify mirror)
			)
		)
		(property "Device Type" "C805H58"
			(at 0.0762 -8.1534 180)
			(unlocked yes)
			(layer "B.Fab")
			(hide yes)
			(effects
				(font
					(size 1.016 1.016)
					(thickness 0.1524)
				)
				(justify mirror)
			)
		)
		(duplicate_pad_numbers_are_jumpers no)
		(fp_line
			(start -0.635 0)
			(end 0.635 0)
			(stroke
				(width 0.508)
				(type default)
			)
			(layer "B.SilkS")
		)
		(fp_rect
			(start 0.9652 1.778)
			(end -0.9652 -1.778)
			(stroke
				(width 0)
				(type default)
			)
			(fill no)
			(layer "B.CrtYd")
		)
		(fp_poly
			(pts
				(xy 0.9652 -1.778) (xy -0.9652 -1.778) (xy -0.9652 1.778) (xy 0.9652 1.778)
			)
			(stroke
				(width 0)
				(type default)
			)
			(fill no)
			(layer "B.Fab")
		)
		(pad "1" smd rect
			(at 0 -0.9652)
			(size 1.397 1.143)
			(layers "B.Cu" "B.Mask" "B.Paste")
			(net "GB_VDDA")
		)
		(pad "2" smd rect
			(at 0 0.9652)
			(size 1.397 1.143)
			(layers "B.Cu" "B.Mask" "B.Paste")
			(net "GND")
		)
	)
	(footprint ""
		(layer "B.Cu")
		(at 82.804 -21.209 180)
		(property "Reference" "PR186"
			(at 0 0 0)
			(layer "B.SilkS")
			(hide yes)
			(effects
				(font
					(size 1.27 1.27)
				)
				(justify mirror)
			)
		)
		(property "Value" "10KR2F-2-GP"
			(at -0.064008 -3.993896 180)
			(unlocked yes)
			(layer "B.Fab")
			(hide yes)
			(effects
				(font
					(size 1.016 1.016)
					(thickness 0.1524)
				)
				(justify mirror)
			)
		)
		(property "Device Type" "R402H16"
			(at -0.064008 -5.517896 180)
			(unlocked yes)
			(layer "B.Fab")
			(hide yes)
			(effects
				(font
					(size 1.016 1.016)
					(thickness 0.1524)
				)
				(justify mirror)
			)
		)
		(duplicate_pad_numbers_are_jumpers no)
		(fp_line
			(start 0.508 -0.9398)
			(end 0.508 0.9398)
			(stroke
				(width 0.1524)
				(type default)
			)
			(layer "B.SilkS")
		)
		(fp_line
			(start -0.508 -0.9398)
			(end 0.508 -0.9398)
			(stroke
				(width 0.1524)
				(type default)
			)
			(layer "B.SilkS")
		)
		(fp_rect
			(start 0.508 0.9398)
			(end -0.508 -0.9398)
			(stroke
				(width 0)
				(type default)
			)
			(fill no)
			(layer "B.CrtYd")
		)
		(fp_rect
			(start 0.508 0.9398)
			(end -0.508 -0.9398)
			(stroke
				(width 0)
				(type default)
			)
			(fill no)
			(layer "B.Fab")
		)
		(pad "1" smd custom
			(at 0 -0.4445)
			(size 0.1397 0.1397)
			(layers "B.Cu" "B.Mask" "B.Paste")
			(net "AGND_P0V9_C")
			(options
				(clearance outline)
				(anchor circle)
			)
			(primitives
				(gr_poly
					(pts
						(arc
							(start -0.1778 0.2794)
							(mid -0.249642 0.249642)
							(end -0.2794 0.1778)
						)
						(arc
							(start -0.2794 -0.1778)
							(mid -0.249642 -0.249642)
							(end -0.1778 -0.2794)
						)
						(arc
							(start 0.1778 -0.2794)
							(mid 0.249642 -0.249642)
							(end 0.2794 -0.1778)
						)
						(arc
							(start 0.2794 0.1778)
							(mid 0.249642 0.249642)
							(end 0.1778 0.2794)
						)
					)
					(width 0)
					(fill yes)
				)
			)
		)
		(pad "2" smd custom
			(at 0 0.4445)
			(size 0.1397 0.1397)
			(layers "B.Cu" "B.Mask" "B.Paste")
			(net "VT235_BIAS")
			(options
				(clearance outline)
				(anchor circle)
			)
			(primitives
				(gr_poly
					(pts
						(arc
							(start -0.1778 0.2794)
							(mid -0.249642 0.249642)
							(end -0.2794 0.1778)
						)
						(arc
							(start -0.2794 -0.1778)
							(mid -0.249642 -0.249642)
							(end -0.1778 -0.2794)
						)
						(arc
							(start 0.1778 -0.2794)
							(mid 0.249642 -0.249642)
							(end 0.2794 -0.1778)
						)
						(arc
							(start 0.2794 0.1778)
							(mid 0.249642 0.249642)
							(end 0.1778 0.2794)
						)
					)
					(width 0)
					(fill yes)
				)
			)
		)
	)
	(footprint ""
		(layer "B.Cu")
		(at 121.419874 -48.333914 -90)
		(property "Reference" "SR618"
			(at 0 0 90)
			(layer "B.SilkS")
			(hide yes)
			(effects
				(font
					(size 1.27 1.27)
				)
				(justify mirror)
			)
		)
		(property "Value" "2K2R2F-GP"
			(at -0.064008 -3.993896 270)
			(unlocked yes)
			(layer "B.Fab")
			(hide yes)
			(effects
				(font
					(size 1.016 1.016)
					(thickness 0.1524)
				)
				(justify mirror)
			)
		)
		(property "Device Type" "R402H16"
			(at -0.064008 -5.517896 270)
			(unlocked yes)
			(layer "B.Fab")
			(hide yes)
			(effects
				(font
					(size 1.016 1.016)
					(thickness 0.1524)
				)
				(justify mirror)
			)
		)
		(duplicate_pad_numbers_are_jumpers no)
		(fp_line
			(start -0.508 -0.9398)
			(end 0.508 -0.9398)
			(stroke
				(width 0.1524)
				(type default)
			)
			(layer "B.SilkS")
		)
		(fp_line
			(start 0.508 -0.9398)
			(end 0.508 0.9398)
			(stroke
				(width 0.1524)
				(type default)
			)
			(layer "B.SilkS")
		)
		(fp_rect
			(start 0.508 0.9398)
			(end -0.508 -0.9398)
			(stroke
				(width 0)
				(type default)
			)
			(fill no)
			(layer "B.CrtYd")
		)
		(fp_rect
			(start 0.508 0.9398)
			(end -0.508 -0.9398)
			(stroke
				(width 0)
				(type default)
			)
			(fill no)
			(layer "B.Fab")
		)
		(pad "1" smd custom
			(at 0 -0.4445 90)
			(size 0.1397 0.1397)
			(layers "B.Cu" "B.Mask" "B.Paste")
			(net "P1V8_C")
			(options
				(clearance outline)
				(anchor circle)
			)
			(primitives
				(gr_poly
					(pts
						(arc
							(start -0.1778 0.2794)
							(mid -0.249642 0.249642)
							(end -0.2794 0.1778)
						)
						(arc
							(start -0.2794 -0.1778)
							(mid -0.249642 -0.249642)
							(end -0.1778 -0.2794)
						)
						(arc
							(start 0.1778 -0.2794)
							(mid 0.249642 -0.249642)
							(end 0.2794 -0.1778)
						)
						(arc
							(start 0.2794 0.1778)
							(mid 0.249642 0.249642)
							(end 0.1778 0.2794)
						)
					)
					(width 0)
					(fill yes)
				)
			)
		)
		(pad "2" smd custom
			(at 0 0.4445 90)
			(size 0.1397 0.1397)
			(layers "B.Cu" "B.Mask" "B.Paste")
			(net "IOC_SCL_1")
			(options
				(clearance outline)
				(anchor circle)
			)
			(primitives
				(gr_poly
					(pts
						(arc
							(start -0.1778 0.2794)
							(mid -0.249642 0.249642)
							(end -0.2794 0.1778)
						)
						(arc
							(start -0.2794 -0.1778)
							(mid -0.249642 -0.249642)
							(end -0.1778 -0.2794)
						)
						(arc
							(start 0.1778 -0.2794)
							(mid 0.249642 -0.249642)
							(end 0.2794 -0.1778)
						)
						(arc
							(start 0.2794 0.1778)
							(mid 0.249642 0.249642)
							(end 0.1778 0.2794)
						)
					)
					(width 0)
					(fill yes)
				)
			)
		)
	)
	(footprint ""
		(layer "B.Cu")
		(at 105.41 -57.15 90)
		(property "Reference" "SR705"
			(at 0 0 90)
			(layer "B.SilkS")
			(hide yes)
			(effects
				(font
					(size 1.27 1.27)
				)
				(justify mirror)
			)
		)
		(property "Value" "10KR2F-2-GP"
			(at -0.064008 -3.993896 90)
			(unlocked yes)
			(layer "B.Fab")
			(hide yes)
			(effects
				(font
					(size 1.016 1.016)
					(thickness 0.1524)
				)
				(justify mirror)
			)
		)
		(property "Device Type" "R402H16"
			(at -0.064008 -5.517896 90)
			(unlocked yes)
			(layer "B.Fab")
			(hide yes)
			(effects
				(font
					(size 1.016 1.016)
					(thickness 0.1524)
				)
				(justify mirror)
			)
		)
		(duplicate_pad_numbers_are_jumpers no)
		(fp_line
			(start 0.508 -0.9398)
			(end 0.508 0.9398)
			(stroke
				(width 0.1524)
				(type default)
			)
			(layer "B.SilkS")
		)
		(fp_line
			(start -0.508 -0.9398)
			(end 0.508 -0.9398)
			(stroke
				(width 0.1524)
				(type default)
			)
			(layer "B.SilkS")
		)
		(fp_rect
			(start 0.508 0.9398)
			(end -0.508 -0.9398)
			(stroke
				(width 0)
				(type default)
			)
			(fill no)
			(layer "B.CrtYd")
		)
		(fp_rect
			(start 0.508 0.9398)
			(end -0.508 -0.9398)
			(stroke
				(width 0)
				(type default)
			)
			(fill no)
			(layer "B.Fab")
		)
		(pad "1" smd custom
			(at 0 -0.4445 270)
			(size 0.1397 0.1397)
			(layers "B.Cu" "B.Mask" "B.Paste")
			(net "P1V8_C")
			(options
				(clearance outline)
				(anchor circle)
			)
			(primitives
				(gr_poly
					(pts
						(arc
							(start -0.1778 0.2794)
							(mid -0.249642 0.249642)
							(end -0.2794 0.1778)
						)
						(arc
							(start -0.2794 -0.1778)
							(mid -0.249642 -0.249642)
							(end -0.1778 -0.2794)
						)
						(arc
							(start 0.1778 -0.2794)
							(mid 0.249642 -0.249642)
							(end 0.2794 -0.1778)
						)
						(arc
							(start 0.2794 0.1778)
							(mid 0.249642 0.249642)
							(end 0.1778 0.2794)
						)
					)
					(width 0)
					(fill yes)
				)
			)
		)
		(pad "2" smd custom
			(at 0 0.4445 270)
			(size 0.1397 0.1397)
			(layers "B.Cu" "B.Mask" "B.Paste")
			(net "XM_NAND_CS_N")
			(options
				(clearance outline)
				(anchor circle)
			)
			(primitives
				(gr_poly
					(pts
						(arc
							(start -0.1778 0.2794)
							(mid -0.249642 0.249642)
							(end -0.2794 0.1778)
						)
						(arc
							(start -0.2794 -0.1778)
							(mid -0.249642 -0.249642)
							(end -0.1778 -0.2794)
						)
						(arc
							(start 0.1778 -0.2794)
							(mid 0.249642 -0.249642)
							(end 0.2794 -0.1778)
						)
						(arc
							(start 0.2794 0.1778)
							(mid 0.249642 0.249642)
							(end 0.1778 0.2794)
						)
					)
					(width 0)
					(fill yes)
				)
			)
		)
	)
	(footprint ""
		(layer "B.Cu")
		(at 108.839 -61.214 -90)
		(property "Reference" "PR182"
			(at 0 0 90)
			(layer "B.SilkS")
			(hide yes)
			(effects
				(font
					(size 1.27 1.27)
				)
				(justify mirror)
			)
		)
		(property "Value" "221R2F-2-GP"
			(at -0.064008 -3.993896 270)
			(unlocked yes)
			(layer "B.Fab")
			(hide yes)
			(effects
				(font
					(size 1.016 1.016)
					(thickness 0.1524)
				)
				(justify mirror)
			)
		)
		(property "Device Type" "R402H16"
			(at -0.064008 -5.517896 270)
			(unlocked yes)
			(layer "B.Fab")
			(hide yes)
			(effects
				(font
					(size 1.016 1.016)
					(thickness 0.1524)
				)
				(justify mirror)
			)
		)
		(duplicate_pad_numbers_are_jumpers no)
		(fp_line
			(start -0.508 -0.9398)
			(end 0.508 -0.9398)
			(stroke
				(width 0.1524)
				(type default)
			)
			(layer "B.SilkS")
		)
		(fp_line
			(start 0.508 -0.9398)
			(end 0.508 0.9398)
			(stroke
				(width 0.1524)
				(type default)
			)
			(layer "B.SilkS")
		)
		(fp_rect
			(start 0.508 0.9398)
			(end -0.508 -0.9398)
			(stroke
				(width 0)
				(type default)
			)
			(fill no)
			(layer "B.CrtYd")
		)
		(fp_rect
			(start 0.508 0.9398)
			(end -0.508 -0.9398)
			(stroke
				(width 0)
				(type default)
			)
			(fill no)
			(layer "B.Fab")
		)
		(pad "1" smd custom
			(at 0 -0.4445 90)
			(size 0.1397 0.1397)
			(layers "B.Cu" "B.Mask" "B.Paste")
			(net "VT235_VFB")
			(options
				(clearance outline)
				(anchor circle)
			)
			(primitives
				(gr_poly
					(pts
						(arc
							(start -0.1778 0.2794)
							(mid -0.249642 0.249642)
							(end -0.2794 0.1778)
						)
						(arc
							(start -0.2794 -0.1778)
							(mid -0.249642 -0.249642)
							(end -0.1778 -0.2794)
						)
						(arc
							(start 0.1778 -0.2794)
							(mid 0.249642 -0.249642)
							(end 0.2794 -0.1778)
						)
						(arc
							(start 0.2794 0.1778)
							(mid 0.249642 0.249642)
							(end 0.1778 0.2794)
						)
					)
					(width 0)
					(fill yes)
				)
			)
		)
		(pad "2" smd custom
			(at 0 0.4445 90)
			(size 0.1397 0.1397)
			(layers "B.Cu" "B.Mask" "B.Paste")
			(net "P0V955_C")
			(options
				(clearance outline)
				(anchor circle)
			)
			(primitives
				(gr_poly
					(pts
						(arc
							(start -0.1778 0.2794)
							(mid -0.249642 0.249642)
							(end -0.2794 0.1778)
						)
						(arc
							(start -0.2794 -0.1778)
							(mid -0.249642 -0.249642)
							(end -0.1778 -0.2794)
						)
						(arc
							(start 0.1778 -0.2794)
							(mid 0.249642 -0.249642)
							(end 0.2794 -0.1778)
						)
						(arc
							(start 0.2794 0.1778)
							(mid 0.249642 0.249642)
							(end 0.1778 0.2794)
						)
					)
					(width 0)
					(fill yes)
				)
			)
		)
	)
)
